(kicad_pcb
	(version 20260206)
	(generator "pcbnew")
	(generator_version "10.0")
	(general
		(thickness 1.6)
		(legacy_teardrops no)
	)
	(paper "A4")
	(title_block
		(title "03242023_DA0F0TMBIJ0_F0T_Motherboard_J_brd_V01_OCP.brd")
		(comment 1 "Grand Teton / footprints 5864-5870 of 6105")
	)
	(layers
		(0 "F.Cu" signal "TOP")
		(4 "In1.Cu" signal "GND")
		(6 "In2.Cu" signal "IN1")
		(8 "In3.Cu" signal "GND1")
		(10 "In4.Cu" signal "IN2")
		(12 "In5.Cu" signal "GND2")
		(14 "In6.Cu" signal "IN3")
		(16 "In7.Cu" signal "GND3")
		(18 "In8.Cu" signal "VCC")
		(20 "In9.Cu" signal "VCC1")
		(22 "In10.Cu" signal "GND4")
		(24 "In11.Cu" signal "IN4")
		(26 "In12.Cu" signal "GND5")
		(28 "In13.Cu" signal "IN5")
		(30 "In14.Cu" signal "GND6")
		(32 "In15.Cu" signal "IN6")
		(34 "In16.Cu" signal "GND7")
		(2 "B.Cu" signal "BOTTOM")
		(9 "F.Adhes" user "F.Adhesive")
		(11 "B.Adhes" user "B.Adhesive")
		(13 "F.Paste" user "Package Geometry/Pastemask Top")
		(15 "B.Paste" user "Package Geometry/Pastemask Bottom")
		(5 "F.SilkS" user "Ref Des/Silkscreen Top")
		(7 "B.SilkS" user "Ref Des/Silkscreen Bottom")
		(1 "F.Mask" user "Board Geometry/Soldermask Top")
		(3 "B.Mask" user "Board Geometry/Soldermask Bottom")
		(17 "Dwgs.User" user "User.Drawings")
		(19 "Cmts.User" user "User.Comments")
		(21 "Eco1.User" user "User.Eco1")
		(23 "Eco2.User" user "User.Eco2")
		(25 "Edge.Cuts" user "Board Geometry/Outline")
		(27 "Margin" user)
		(31 "F.CrtYd" user "Package Geometry/Place Bound Top")
		(29 "B.CrtYd" user "Package Geometry/Place Bound Bottom")
		(35 "F.Fab" user "Ref Des/Assembly Top")
		(33 "B.Fab" user "Ref Des/Assembly Bottom")
	)
	(footprint ""
		(layer "B.Cu")
		(at 157.0355 -8.801608 180)
		(property "Reference" "R2204"
			(at 0 0 0)
			(layer "B.SilkS")
			(hide yes)
			(effects
				(font
					(size 1.27 1.27)
				)
				(justify mirror)
			)
		)
		(property "Value" ""
			(at 0 0 0)
			(layer "B.Fab")
			(effects
				(font
					(size 1.27 1.27)
				)
				(justify mirror)
			)
		)
		(duplicate_pad_numbers_are_jumpers no)
		(fp_line
			(start 0.7874 0.4064)
			(end 0.7874 -0.4064)
			(stroke
				(width 0.1524)
				(type default)
			)
			(layer "B.SilkS")
		)
		(fp_line
			(start 0.7874 -0.4064)
			(end -0.7874 -0.4064)
			(stroke
				(width 0.1524)
				(type default)
			)
			(layer "B.SilkS")
		)
		(fp_line
			(start -0.7874 0.4064)
			(end 0.7874 0.4064)
			(stroke
				(width 0.1524)
				(type default)
			)
			(layer "B.SilkS")
		)
		(fp_line
			(start -0.7874 -0.4064)
			(end -0.7874 0.4064)
			(stroke
				(width 0.1524)
				(type default)
			)
			(layer "B.SilkS")
		)
		(fp_line
			(start 0.67945 0.3048)
			(end 0.67945 -0.305054)
			(stroke
				(width 0.1)
				(type default)
			)
			(layer "B.Fab")
		)
		(fp_line
			(start 0.67945 -0.305054)
			(end 0.12065 -0.305054)
			(stroke
				(width 0.1)
				(type default)
			)
			(layer "B.Fab")
		)
		(fp_line
			(start 0.12065 0.3048)
			(end 0.67945 0.3048)
			(stroke
				(width 0.1)
				(type default)
			)
			(layer "B.Fab")
		)
		(fp_line
			(start 0.12065 0.2794)
			(end 0.12065 0.3048)
			(stroke
				(width 0.1)
				(type default)
			)
			(layer "B.Fab")
		)
		(fp_line
			(start 0.12065 -0.2794)
			(end -0.12065 -0.2794)
			(stroke
				(width 0.1)
				(type default)
			)
			(layer "B.Fab")
		)
		(fp_line
			(start 0.12065 -0.305054)
			(end 0.12065 -0.2794)
			(stroke
				(width 0.1)
				(type default)
			)
			(layer "B.Fab")
		)
		(fp_line
			(start -0.120396 0.3048)
			(end -0.120396 0.2794)
			(stroke
				(width 0.1)
				(type default)
			)
			(layer "B.Fab")
		)
		(fp_line
			(start -0.120396 0.2794)
			(end 0.12065 0.2794)
			(stroke
				(width 0.1)
				(type default)
			)
			(layer "B.Fab")
		)
		(fp_line
			(start -0.12065 -0.2794)
			(end -0.12065 -0.3048)
			(stroke
				(width 0.1)
				(type default)
			)
			(layer "B.Fab")
		)
		(fp_line
			(start -0.12065 -0.3048)
			(end -0.67945 -0.3048)
			(stroke
				(width 0.1)
				(type default)
			)
			(layer "B.Fab")
		)
		(fp_line
			(start -0.67945 0.3048)
			(end -0.120396 0.3048)
			(stroke
				(width 0.1)
				(type default)
			)
			(layer "B.Fab")
		)
		(fp_line
			(start -0.67945 -0.3048)
			(end -0.67945 0.3048)
			(stroke
				(width 0.1)
				(type default)
			)
			(layer "B.Fab")
		)
		(pad "1" smd circle
			(at 0.40005 0)
			(size 0 0)
			(layers "B.Cu" "B.Mask" "B.Paste")
			(net "P3V3_AUX")
		)
		(pad "2" smd circle
			(at -0.40005 0)
			(size 0 0)
			(layers "B.Cu" "B.Mask" "B.Paste")
			(net "SMB_PCIE0_3V3AUX_SCL")
		)
	)
	(footprint ""
		(layer "B.Cu")
		(at 333.569056 -58.473086 -90)
		(property "Reference" "C1186"
			(at 0 0 90)
			(layer "B.SilkS")
			(hide yes)
			(effects
				(font
					(size 1.27 1.27)
				)
				(justify mirror)
			)
		)
		(property "Value" ""
			(at 0 0 90)
			(layer "B.Fab")
			(effects
				(font
					(size 1.27 1.27)
				)
				(justify mirror)
			)
		)
		(duplicate_pad_numbers_are_jumpers no)
		(fp_line
			(start -1.2954 0.5842)
			(end 1.2954 0.5842)
			(stroke
				(width 0.1524)
				(type default)
			)
			(layer "B.SilkS")
		)
		(fp_line
			(start 1.2954 0.5842)
			(end 1.2954 -0.5842)
			(stroke
				(width 0.1524)
				(type default)
			)
			(layer "B.SilkS")
		)
		(fp_line
			(start -1.2954 -0.5842)
			(end -1.2954 0.5842)
			(stroke
				(width 0.1524)
				(type default)
			)
			(layer "B.SilkS")
		)
		(fp_line
			(start 0 -0.5842)
			(end 0 0.5842)
			(stroke
				(width 0.1524)
				(type default)
			)
			(layer "B.SilkS")
		)
		(fp_line
			(start 1.2954 -0.5842)
			(end -1.2954 -0.5842)
			(stroke
				(width 0.1524)
				(type default)
			)
			(layer "B.SilkS")
		)
		(fp_line
			(start -0.8636 0.4572)
			(end 0.8636 0.4572)
			(stroke
				(width 0.1)
				(type default)
			)
			(layer "B.Fab")
		)
		(fp_line
			(start 0.8636 0.4572)
			(end 0.8636 0.4064)
			(stroke
				(width 0.1)
				(type default)
			)
			(layer "B.Fab")
		)
		(fp_line
			(start -1.1938 0.4064)
			(end -0.8636 0.4064)
			(stroke
				(width 0.1)
				(type default)
			)
			(layer "B.Fab")
		)
		(fp_line
			(start -0.8636 0.4064)
			(end -0.8636 0.4572)
			(stroke
				(width 0.1)
				(type default)
			)
			(layer "B.Fab")
		)
		(fp_line
			(start 0.8636 0.4064)
			(end 1.1938 0.4064)
			(stroke
				(width 0.1)
				(type default)
			)
			(layer "B.Fab")
		)
		(fp_line
			(start 1.1938 0.4064)
			(end 1.1938 -0.4064)
			(stroke
				(width 0.1)
				(type default)
			)
			(layer "B.Fab")
		)
		(fp_line
			(start -1.1938 -0.4064)
			(end -1.1938 0.4064)
			(stroke
				(width 0.1)
				(type default)
			)
			(layer "B.Fab")
		)
		(fp_line
			(start -0.8636 -0.4064)
			(end -1.1938 -0.4064)
			(stroke
				(width 0.1)
				(type default)
			)
			(layer "B.Fab")
		)
		(fp_line
			(start 0.8636 -0.4064)
			(end 0.8636 -0.4572)
			(stroke
				(width 0.1)
				(type default)
			)
			(layer "B.Fab")
		)
		(fp_line
			(start 1.1938 -0.4064)
			(end 0.8636 -0.4064)
			(stroke
				(width 0.1)
				(type default)
			)
			(layer "B.Fab")
		)
		(fp_line
			(start -0.8636 -0.4572)
			(end -0.8636 -0.4064)
			(stroke
				(width 0.1)
				(type default)
			)
			(layer "B.Fab")
		)
		(fp_line
			(start 0.8636 -0.4572)
			(end -0.8636 -0.4572)
			(stroke
				(width 0.1)
				(type default)
			)
			(layer "B.Fab")
		)
		(pad "1" smd rect
			(at 0.7366 0 180)
			(size 0.7112 0.8128)
			(layers "B.Cu" "B.Mask" "B.Paste")
			(net "P1V8_PCH_AUX")
		)
		(pad "2" smd rect
			(at -0.7366 0 180)
			(size 0.7112 0.8128)
			(layers "B.Cu" "B.Mask" "B.Paste")
			(net "GND")
		)
	)
	(footprint ""
		(layer "B.Cu")
		(at 65.364868 -195.632578 -90)
		(property "Reference" "R4300"
			(at 0 0 90)
			(layer "B.SilkS")
			(hide yes)
			(effects
				(font
					(size 1.27 1.27)
				)
				(justify mirror)
			)
		)
		(property "Value" ""
			(at 0 0 90)
			(layer "B.Fab")
			(effects
				(font
					(size 1.27 1.27)
				)
				(justify mirror)
			)
		)
		(duplicate_pad_numbers_are_jumpers no)
		(fp_line
			(start -0.7874 0.4064)
			(end 0.7874 0.4064)
			(stroke
				(width 0.1524)
				(type default)
			)
			(layer "B.SilkS")
		)
		(fp_line
			(start 0.7874 0.4064)
			(end 0.7874 -0.4064)
			(stroke
				(width 0.1524)
				(type default)
			)
			(layer "B.SilkS")
		)
		(fp_line
			(start -0.7874 -0.4064)
			(end -0.7874 0.4064)
			(stroke
				(width 0.1524)
				(type default)
			)
			(layer "B.SilkS")
		)
		(fp_line
			(start 0.7874 -0.4064)
			(end -0.7874 -0.4064)
			(stroke
				(width 0.1524)
				(type default)
			)
			(layer "B.SilkS")
		)
		(fp_line
			(start -0.67945 0.3048)
			(end -0.120396 0.3048)
			(stroke
				(width 0.1)
				(type default)
			)
			(layer "B.Fab")
		)
		(fp_line
			(start -0.120396 0.3048)
			(end -0.120396 0.2794)
			(stroke
				(width 0.1)
				(type default)
			)
			(layer "B.Fab")
		)
		(fp_line
			(start 0.12065 0.3048)
			(end 0.67945 0.3048)
			(stroke
				(width 0.1)
				(type default)
			)
			(layer "B.Fab")
		)
		(fp_line
			(start 0.67945 0.3048)
			(end 0.67945 -0.305054)
			(stroke
				(width 0.1)
				(type default)
			)
			(layer "B.Fab")
		)
		(fp_line
			(start -0.120396 0.2794)
			(end 0.12065 0.2794)
			(stroke
				(width 0.1)
				(type default)
			)
			(layer "B.Fab")
		)
		(fp_line
			(start 0.12065 0.2794)
			(end 0.12065 0.3048)
			(stroke
				(width 0.1)
				(type default)
			)
			(layer "B.Fab")
		)
		(fp_line
			(start -0.12065 -0.2794)
			(end -0.12065 -0.3048)
			(stroke
				(width 0.1)
				(type default)
			)
			(layer "B.Fab")
		)
		(fp_line
			(start 0.12065 -0.2794)
			(end -0.12065 -0.2794)
			(stroke
				(width 0.1)
				(type default)
			)
			(layer "B.Fab")
		)
		(fp_line
			(start -0.67945 -0.3048)
			(end -0.67945 0.3048)
			(stroke
				(width 0.1)
				(type default)
			)
			(layer "B.Fab")
		)
		(fp_line
			(start -0.12065 -0.3048)
			(end -0.67945 -0.3048)
			(stroke
				(width 0.1)
				(type default)
			)
			(layer "B.Fab")
		)
		(fp_line
			(start 0.12065 -0.305054)
			(end 0.12065 -0.2794)
			(stroke
				(width 0.1)
				(type default)
			)
			(layer "B.Fab")
		)
		(fp_line
			(start 0.67945 -0.305054)
			(end 0.12065 -0.305054)
			(stroke
				(width 0.1)
				(type default)
			)
			(layer "B.Fab")
		)
		(pad "1" smd circle
			(at 0.40005 0 90)
			(size 0 0)
			(layers "B.Cu" "B.Mask" "B.Paste")
			(net "PWRGD_DRAMPWRGD_CPU1_CD_LVC1_R2")
		)
		(pad "2" smd circle
			(at -0.40005 0 90)
			(size 0 0)
			(layers "B.Cu" "B.Mask" "B.Paste")
			(net "PWRGD_DRAMPWRGD_CPU1_CD_LVC1_R")
		)
	)
	(footprint ""
		(layer "B.Cu")
		(at 383.429256 -343.927938 -90)
		(property "Reference" "PR134"
			(at 0 0 90)
			(layer "B.SilkS")
			(hide yes)
			(effects
				(font
					(size 1.27 1.27)
				)
				(justify mirror)
			)
		)
		(property "Value" ""
			(at 0 0 90)
			(layer "B.Fab")
			(effects
				(font
					(size 1.27 1.27)
				)
				(justify mirror)
			)
		)
		(duplicate_pad_numbers_are_jumpers no)
		(fp_line
			(start -0.7874 0.4064)
			(end 0.7874 0.4064)
			(stroke
				(width 0.1524)
				(type default)
			)
			(layer "B.SilkS")
		)
		(fp_line
			(start 0.7874 0.4064)
			(end 0.7874 -0.4064)
			(stroke
				(width 0.1524)
				(type default)
			)
			(layer "B.SilkS")
		)
		(fp_line
			(start -0.7874 -0.4064)
			(end -0.7874 0.4064)
			(stroke
				(width 0.1524)
				(type default)
			)
			(layer "B.SilkS")
		)
		(fp_line
			(start 0.7874 -0.4064)
			(end -0.7874 -0.4064)
			(stroke
				(width 0.1524)
				(type default)
			)
			(layer "B.SilkS")
		)
		(fp_line
			(start -0.67945 0.3048)
			(end -0.120396 0.3048)
			(stroke
				(width 0.1)
				(type default)
			)
			(layer "B.Fab")
		)
		(fp_line
			(start -0.120396 0.3048)
			(end -0.120396 0.2794)
			(stroke
				(width 0.1)
				(type default)
			)
			(layer "B.Fab")
		)
		(fp_line
			(start 0.12065 0.3048)
			(end 0.67945 0.3048)
			(stroke
				(width 0.1)
				(type default)
			)
			(layer "B.Fab")
		)
		(fp_line
			(start 0.67945 0.3048)
			(end 0.67945 -0.305054)
			(stroke
				(width 0.1)
				(type default)
			)
			(layer "B.Fab")
		)
		(fp_line
			(start -0.120396 0.2794)
			(end 0.12065 0.2794)
			(stroke
				(width 0.1)
				(type default)
			)
			(layer "B.Fab")
		)
		(fp_line
			(start 0.12065 0.2794)
			(end 0.12065 0.3048)
			(stroke
				(width 0.1)
				(type default)
			)
			(layer "B.Fab")
		)
		(fp_line
			(start -0.12065 -0.2794)
			(end -0.12065 -0.3048)
			(stroke
				(width 0.1)
				(type default)
			)
			(layer "B.Fab")
		)
		(fp_line
			(start 0.12065 -0.2794)
			(end -0.12065 -0.2794)
			(stroke
				(width 0.1)
				(type default)
			)
			(layer "B.Fab")
		)
		(fp_line
			(start -0.67945 -0.3048)
			(end -0.67945 0.3048)
			(stroke
				(width 0.1)
				(type default)
			)
			(layer "B.Fab")
		)
		(fp_line
			(start -0.12065 -0.3048)
			(end -0.67945 -0.3048)
			(stroke
				(width 0.1)
				(type default)
			)
			(layer "B.Fab")
		)
		(fp_line
			(start 0.12065 -0.305054)
			(end 0.12065 -0.2794)
			(stroke
				(width 0.1)
				(type default)
			)
			(layer "B.Fab")
		)
		(fp_line
			(start 0.67945 -0.305054)
			(end 0.12065 -0.305054)
			(stroke
				(width 0.1)
				(type default)
			)
			(layer "B.Fab")
		)
		(pad "1" smd circle
			(at 0.40005 0 90)
			(size 0 0)
			(layers "B.Cu" "B.Mask" "B.Paste")
			(net "PVCCIN_CPU0_PVCC")
		)
		(pad "2" smd circle
			(at -0.40005 0 90)
			(size 0 0)
			(layers "B.Cu" "B.Mask" "B.Paste")
			(net "PVCCIN_CPU0_VDD8")
		)
	)
	(footprint ""
		(layer "B.Cu")
		(at 322.682616 -66.937128 -90)
		(property "Reference" "C1245"
			(at 0 0 90)
			(layer "B.SilkS")
			(hide yes)
			(effects
				(font
					(size 1.27 1.27)
				)
				(justify mirror)
			)
		)
		(property "Value" ""
			(at 0 0 90)
			(layer "B.Fab")
			(effects
				(font
					(size 1.27 1.27)
				)
				(justify mirror)
			)
		)
		(duplicate_pad_numbers_are_jumpers no)
		(fp_line
			(start -1.524 0.762)
			(end 1.524 0.762)
			(stroke
				(width 0.1524)
				(type default)
			)
			(layer "B.SilkS")
		)
		(fp_line
			(start 1.524 0.762)
			(end 1.524 -0.762)
			(stroke
				(width 0.1524)
				(type default)
			)
			(layer "B.SilkS")
		)
		(fp_line
			(start -1.524 -0.762)
			(end -1.524 0.762)
			(stroke
				(width 0.1524)
				(type default)
			)
			(layer "B.SilkS")
		)
		(fp_line
			(start 1.524 -0.762)
			(end -1.524 -0.762)
			(stroke
				(width 0.1524)
				(type default)
			)
			(layer "B.SilkS")
		)
		(fp_line
			(start -1.1049 0.724916)
			(end -1.1049 -0.724916)
			(stroke
				(width 0.1)
				(type default)
			)
			(layer "B.Fab")
		)
		(fp_line
			(start 1.1049 0.724916)
			(end -1.1049 0.724916)
			(stroke
				(width 0.1)
				(type default)
			)
			(layer "B.Fab")
		)
		(fp_line
			(start -1.1049 -0.724916)
			(end 1.1049 -0.724916)
			(stroke
				(width 0.1)
				(type default)
			)
			(layer "B.Fab")
		)
		(fp_line
			(start 1.1049 -0.724916)
			(end 1.1049 0.724916)
			(stroke
				(width 0.1)
				(type default)
			)
			(layer "B.Fab")
		)
		(pad "1" smd rect
			(at 0.889 0 270)
			(size 1.016 1.27)
			(layers "B.Cu" "B.Mask" "B.Paste")
			(net "P3V3_AUX")
		)
		(pad "2" smd rect
			(at -0.889 0 270)
			(size 1.016 1.27)
			(layers "B.Cu" "B.Mask" "B.Paste")
			(net "GND")
		)
	)
	(footprint ""
		(layer "B.Cu")
		(at 201.962258 -192.64757)
		(property "Reference" "R738"
			(at 0 0 0)
			(layer "B.SilkS")
			(hide yes)
			(effects
				(font
					(size 1.27 1.27)
				)
				(justify mirror)
			)
		)
		(property "Value" ""
			(at 0 0 0)
			(layer "B.Fab")
			(effects
				(font
					(size 1.27 1.27)
				)
				(justify mirror)
			)
		)
		(duplicate_pad_numbers_are_jumpers no)
		(fp_line
			(start -0.7874 -0.4064)
			(end -0.7874 0.4064)
			(stroke
				(width 0.1524)
				(type default)
			)
			(layer "B.SilkS")
		)
		(fp_line
			(start -0.7874 0.4064)
			(end 0.7874 0.4064)
			(stroke
				(width 0.1524)
				(type default)
			)
			(layer "B.SilkS")
		)
		(fp_line
			(start 0.7874 -0.4064)
			(end -0.7874 -0.4064)
			(stroke
				(width 0.1524)
				(type default)
			)
			(layer "B.SilkS")
		)
		(fp_line
			(start 0.7874 0.4064)
			(end 0.7874 -0.4064)
			(stroke
				(width 0.1524)
				(type default)
			)
			(layer "B.SilkS")
		)
		(fp_line
			(start -0.67945 -0.3048)
			(end -0.67945 0.3048)
			(stroke
				(width 0.1)
				(type default)
			)
			(layer "B.Fab")
		)
		(fp_line
			(start -0.67945 0.3048)
			(end -0.120396 0.3048)
			(stroke
				(width 0.1)
				(type default)
			)
			(layer "B.Fab")
		)
		(fp_line
			(start -0.12065 -0.3048)
			(end -0.67945 -0.3048)
			(stroke
				(width 0.1)
				(type default)
			)
			(layer "B.Fab")
		)
		(fp_line
			(start -0.12065 -0.2794)
			(end -0.12065 -0.3048)
			(stroke
				(width 0.1)
				(type default)
			)
			(layer "B.Fab")
		)
		(fp_line
			(start -0.120396 0.2794)
			(end 0.12065 0.2794)
			(stroke
				(width 0.1)
				(type default)
			)
			(layer "B.Fab")
		)
		(fp_line
			(start -0.120396 0.3048)
			(end -0.120396 0.2794)
			(stroke
				(width 0.1)
				(type default)
			)
			(layer "B.Fab")
		)
		(fp_line
			(start 0.12065 -0.305054)
			(end 0.12065 -0.2794)
			(stroke
				(width 0.1)
				(type default)
			)
			(layer "B.Fab")
		)
		(fp_line
			(start 0.12065 -0.2794)
			(end -0.12065 -0.2794)
			(stroke
				(width 0.1)
				(type default)
			)
			(layer "B.Fab")
		)
		(fp_line
			(start 0.12065 0.2794)
			(end 0.12065 0.3048)
			(stroke
				(width 0.1)
				(type default)
			)
			(layer "B.Fab")
		)
		(fp_line
			(start 0.12065 0.3048)
			(end 0.67945 0.3048)
			(stroke
				(width 0.1)
				(type default)
			)
			(layer "B.Fab")
		)
		(fp_line
			(start 0.67945 -0.305054)
			(end 0.12065 -0.305054)
			(stroke
				(width 0.1)
				(type default)
			)
			(layer "B.Fab")
		)
		(fp_line
			(start 0.67945 0.3048)
			(end 0.67945 -0.305054)
			(stroke
				(width 0.1)
				(type default)
			)
			(layer "B.Fab")
		)
		(pad "1" smd circle
			(at 0.40005 0 180)
			(size 0 0)
			(layers "B.Cu" "B.Mask" "B.Paste")
			(net "FM_CPU0_SKTOCC_LVT3_N")
		)
		(pad "2" smd circle
			(at -0.40005 0 180)
			(size 0 0)
			(layers "B.Cu" "B.Mask" "B.Paste")
			(net "FM_CPU0_SKTOCC_N")
		)
	)
	(footprint ""
		(layer "B.Cu")
		(at 490.2708 -342.785192)
		(property "Reference" "DB14"
			(at 2.639822 -5.63118 270)
			(unlocked yes)
			(layer "B.SilkS")
			(effects
				(font
					(size 0.7874 0.5842)
					(thickness 0.1524)
				)
				(justify left mirror)
			)
		)
		(property "Value" ""
			(at 0 0 0)
			(layer "B.Fab")
			(effects
				(font
					(size 1.27 1.27)
				)
				(justify mirror)
			)
		)
		(duplicate_pad_numbers_are_jumpers no)
		(fp_line
			(start -3.330702 -4.771136)
			(end 0 4.011168)
			(stroke
				(width 0.1524)
				(type default)
			)
			(layer "B.SilkS")
		)
		(fp_line
			(start 0 4.011168)
			(end 3.330702 -4.771136)
			(stroke
				(width 0.1524)
				(type default)
			)
			(layer "B.SilkS")
		)
		(fp_line
			(start 3.330702 -4.771136)
			(end -3.330702 -4.771136)
			(stroke
				(width 0.1524)
				(type default)
			)
			(layer "B.SilkS")
		)
		(fp_line
			(start -3.330702 -4.771136)
			(end 0 4.011168)
			(stroke
				(width 0.1)
				(type default)
			)
			(layer "B.Fab")
		)
		(fp_line
			(start 0 4.011168)
			(end 3.330702 -4.771136)
			(stroke
				(width 0.1)
				(type default)
			)
			(layer "B.Fab")
		)
		(fp_line
			(start 3.330702 -4.771136)
			(end -3.330702 -4.771136)
			(stroke
				(width 0.1)
				(type default)
			)
			(layer "B.Fab")
		)
		(pad "1" thru_hole circle
			(at 0 0 180)
			(size 2.159 2.159)
			(drill 1.7018)
			(layers "*.Cu" "*.Mask")
			(remove_unused_layers no)
			(net "T1_GND")
			(clearance 0.0254)
			(thermal_gap 0.0254)
		)
		(pad "2" thru_hole circle
			(at 1.27 -3.348736 180)
			(size 2.159 2.159)
			(drill 1.7018)
			(layers "*.Cu" "*.Mask")
			(remove_unused_layers no)
			(net "TDR_SE_40_OHM_IN6")
			(clearance 0.0254)
			(thermal_gap 0.0254)
		)
		(pad "3" thru_hole circle
			(at -1.27 -3.348736 180)
			(size 2.159 2.159)
			(drill 1.7018)
			(layers "*.Cu" "*.Mask")
			(remove_unused_layers no)
			(net "TDR_SE_40_OHM_IN6")
			(clearance 0.0254)
			(thermal_gap 0.0254)
		)
	)
)
